G04*
G04 #@! TF.GenerationSoftware,Altium Limited,Altium Designer,23.0.1 (38)*
G04*
G04 Layer_Color=8421504*
%FSLAX44Y44*%
%MOMM*%
G71*
G04*
G04 #@! TF.SameCoordinates,9A23C038-B079-480F-8166-AFFB5740F5AE*
G04*
G04*
G04 #@! TF.FilePolarity,Positive*
G04*
G01*
G75*
%ADD18R,0.5969X0.8954*%
%ADD19R,0.8001X1.2065*%
%ADD20R,1.2700X0.5588*%
%ADD21R,0.9000X0.6000*%
%ADD22R,0.5000X0.6000*%
%ADD23R,0.8000X0.8000*%
%ADD24R,0.5000X0.4000*%
%ADD25R,2.9500X1.0200*%
%ADD26R,5.0000X1.0000*%
%ADD27C,1.0000*%
%ADD28R,0.5000X0.5000*%
%ADD29R,0.5000X0.5000*%
%ADD30R,0.6000X0.5000*%
G36*
X40923Y183315D02*
X40935Y183301D01*
X40946Y183287D01*
X41000Y183228D01*
X41053Y183168D01*
X41067Y183156D01*
X41079Y183142D01*
X43342Y180919D01*
X43385Y180880D01*
X43426Y180841D01*
X43458Y180815D01*
X43489Y180788D01*
X43535Y180754D01*
X43580Y180718D01*
X46160Y178872D01*
X46208Y178841D01*
X46255Y178808D01*
X46290Y178788D01*
X46325Y178765D01*
X46376Y178739D01*
X46426Y178711D01*
X49260Y177285D01*
X49313Y177262D01*
X49364Y177237D01*
X49403Y177223D01*
X49440Y177206D01*
X49494Y177188D01*
X49548Y177168D01*
X52569Y176198D01*
X52624Y176183D01*
X52679Y176166D01*
X52719Y176158D01*
X52759Y176147D01*
X52815Y176138D01*
X52871Y176126D01*
X56006Y175636D01*
X56063Y175629D01*
X56119Y175621D01*
X56160Y175619D01*
X56201Y175615D01*
X56258Y175614D01*
X56315Y175611D01*
X59488D01*
X59545Y175614D01*
X59602Y175615D01*
X59643Y175619D01*
X59684Y175621D01*
X59741Y175629D01*
X59798Y175636D01*
X62932Y176126D01*
X62989Y176138D01*
X63045Y176147D01*
X63085Y176158D01*
X63125Y176166D01*
X63179Y176183D01*
X63235Y176198D01*
X66256Y177168D01*
X66309Y177188D01*
X66364Y177206D01*
X66401Y177223D01*
X66439Y177237D01*
X66491Y177262D01*
X66543Y177285D01*
X69378Y178711D01*
X69427Y178739D01*
X69478Y178765D01*
X69513Y178788D01*
X69549Y178808D01*
X69595Y178841D01*
X69644Y178872D01*
X72223Y180718D01*
X72268Y180754D01*
X72315Y180788D01*
X72345Y180815D01*
X72377Y180841D01*
X72418Y180880D01*
X72461Y180919D01*
X74724Y183142D01*
X74737Y183156D01*
X74750Y183168D01*
X74803Y183228D01*
X74858Y183287D01*
X74869Y183301D01*
X74881Y183315D01*
X75275Y183805D01*
X91459Y183805D01*
Y164188D01*
X24344D01*
Y183805D01*
X40528D01*
X40923Y183315D01*
D02*
G37*
G36*
X59837Y204378D02*
X61044Y203878D01*
X62130Y203152D01*
X63054Y202228D01*
X63780Y201141D01*
X64280Y199934D01*
X64535Y198652D01*
Y197999D01*
Y197346D01*
X64280Y196064D01*
X63780Y194857D01*
X63054Y193771D01*
X62130Y192847D01*
X61044Y192120D01*
X59837Y191621D01*
X58555Y191366D01*
X57248D01*
X55967Y191621D01*
X54760Y192120D01*
X53673Y192847D01*
X52749Y193771D01*
X52023Y194857D01*
X51523Y196064D01*
X51268Y197346D01*
Y197999D01*
Y198653D01*
X51523Y199934D01*
X52023Y201141D01*
X52749Y202228D01*
X53673Y203152D01*
X54760Y203878D01*
X55967Y204378D01*
X57248Y204633D01*
X58555D01*
X59837Y204378D01*
D02*
G37*
G36*
X91459Y212194D02*
X75275D01*
X74881Y212683D01*
X74869Y212697D01*
X74858Y212712D01*
X74803Y212771D01*
X74750Y212830D01*
X74737Y212843D01*
X74724Y212856D01*
X72461Y215080D01*
X72418Y215118D01*
X72377Y215158D01*
X72345Y215183D01*
X72315Y215211D01*
X72269Y215244D01*
X72223Y215280D01*
X69644Y217127D01*
X69595Y217158D01*
X69549Y217190D01*
X69513Y217211D01*
X69478Y217233D01*
X69427Y217259D01*
X69378Y217287D01*
X66543Y218713D01*
X66491Y218736D01*
X66439Y218761D01*
X66401Y218776D01*
X66364Y218792D01*
X66309Y218810D01*
X66256Y218831D01*
X63235Y219800D01*
X63179Y219815D01*
X63125Y219832D01*
X63085Y219840D01*
X63045Y219851D01*
X62989Y219860D01*
X62932Y219872D01*
X59798Y220363D01*
X59741Y220369D01*
X59684Y220377D01*
X59643Y220379D01*
X59602Y220384D01*
X59545Y220384D01*
X59488Y220387D01*
X56315D01*
X56258Y220384D01*
X56201Y220384D01*
X56160Y220379D01*
X56119Y220377D01*
X56063Y220369D01*
X56006Y220363D01*
X52871Y219872D01*
X52815Y219860D01*
X52759Y219851D01*
X52719Y219841D01*
X52679Y219832D01*
X52624Y219815D01*
X52569Y219800D01*
X49548Y218831D01*
X49494Y218810D01*
X49440Y218792D01*
X49403Y218776D01*
X49364Y218761D01*
X49313Y218736D01*
X49260Y218713D01*
X46426Y217287D01*
X46376Y217259D01*
X46325Y217233D01*
X46291Y217211D01*
X46255Y217190D01*
X46208Y217158D01*
X46160Y217127D01*
X43580Y215280D01*
X43535Y215244D01*
X43489Y215211D01*
X43458Y215183D01*
X43426Y215158D01*
X43385Y215118D01*
X43342Y215080D01*
X41079Y212856D01*
X41067Y212843D01*
X41053Y212830D01*
X41000Y212771D01*
X40946Y212712D01*
X40935Y212697D01*
X40923Y212683D01*
X40528Y212194D01*
X24344D01*
Y231811D01*
X91459D01*
Y212194D01*
D02*
G37*
D18*
X236990Y101364D02*
D03*
X247990Y101364D02*
D03*
X258990Y101364D02*
D03*
X269990Y101364D02*
D03*
X280990D02*
D03*
X310990D02*
D03*
X321990D02*
D03*
X332990D02*
D03*
X343990D02*
D03*
X354990D02*
D03*
X365990D02*
D03*
X376990D02*
D03*
X236990Y208632D02*
D03*
X247990Y208632D02*
D03*
X258990Y208632D02*
D03*
X269990Y208632D02*
D03*
X280990D02*
D03*
X310989Y208632D02*
D03*
X321990Y208632D02*
D03*
X332990Y208632D02*
D03*
X343989D02*
D03*
X354990Y208632D02*
D03*
X365989Y208632D02*
D03*
X376990Y208632D02*
D03*
D19*
X236990Y90950D02*
D03*
X247990Y90950D02*
D03*
X258990Y90950D02*
D03*
X269990Y90950D02*
D03*
X280990D02*
D03*
X310990D02*
D03*
X321990D02*
D03*
X332990D02*
D03*
X343990D02*
D03*
X354990D02*
D03*
X365990D02*
D03*
X376990D02*
D03*
X236990Y219046D02*
D03*
X247990Y219046D02*
D03*
X258990Y219046D02*
D03*
X269990Y219046D02*
D03*
X280990D02*
D03*
X310990D02*
D03*
X321990D02*
D03*
X332990Y219046D02*
D03*
X343989D02*
D03*
X354990Y219046D02*
D03*
X365989Y219046D02*
D03*
X376990Y219046D02*
D03*
D20*
X130652Y120850D02*
D03*
Y139150D02*
D03*
X111348Y130000D02*
D03*
D21*
X110000Y174384D02*
D03*
Y159383D02*
D03*
D22*
X95000Y104000D02*
D03*
X105000D02*
D03*
X382000Y254000D02*
D03*
X392000D02*
D03*
X136000Y104000D02*
D03*
X126000D02*
D03*
X221000Y72000D02*
D03*
X231000D02*
D03*
D23*
X510492Y112246D02*
D03*
Y97246D02*
D03*
X441492Y112246D02*
D03*
Y97246D02*
D03*
D24*
X107877Y190000D02*
D03*
Y198000D02*
D03*
D25*
X633450Y82800D02*
D03*
Y102800D02*
D03*
Y122800D02*
D03*
Y142800D02*
D03*
X587950Y82800D02*
D03*
Y102800D02*
D03*
Y122800D02*
D03*
Y142800D02*
D03*
D26*
X57900Y168839D02*
D03*
X55360Y225940D02*
D03*
D27*
X57902Y197999D02*
D03*
D28*
X138000Y174384D02*
D03*
X128000D02*
D03*
D29*
X352000Y62000D02*
D03*
Y72000D02*
D03*
X367557Y62000D02*
D03*
Y72000D02*
D03*
X382990Y62000D02*
D03*
Y72000D02*
D03*
X248008Y249000D02*
D03*
Y239000D02*
D03*
D30*
X293000Y248000D02*
D03*
Y238000D02*
D03*
X459000Y114000D02*
D03*
Y104000D02*
D03*
X528000Y114000D02*
D03*
Y104000D02*
D03*
X585060Y190000D02*
D03*
Y200000D02*
D03*
X610611Y190000D02*
D03*
Y200000D02*
D03*
M02*
